(kicad_pcb
	(version 20241229)
	(generator "pcbnew")
	(generator_version "9.0")
	(general
		(thickness 1.294)
		(legacy_teardrops no)
	)
	(paper "A3")
	(title_block
		(title "Kintex 410T devboard")
		(date "2024-04-03")
		(rev "1.1.2")
		(comment 9 "footprints 746-751 of 975")
	)
	(layers
		(0 "F.Cu" mixed)
		(4 "In1.Cu" power)
		(6 "In2.Cu" power)
		(8 "In3.Cu" mixed)
		(10 "In4.Cu" power)
		(12 "In5.Cu" mixed)
		(14 "In6.Cu" power)
		(16 "In7.Cu" mixed)
		(18 "In8.Cu" power)
		(2 "B.Cu" mixed)
		(9 "F.Adhes" user "F.Adhesive")
		(11 "B.Adhes" user "B.Adhesive")
		(13 "F.Paste" user)
		(15 "B.Paste" user)
		(5 "F.SilkS" user "F.Silkscreen")
		(7 "B.SilkS" user "B.Silkscreen")
		(1 "F.Mask" user)
		(3 "B.Mask" user)
		(17 "Dwgs.User" user "User.Drawings")
		(19 "Cmts.User" user "User.Comments")
		(21 "Eco1.User" user "User.Eco1")
		(23 "Eco2.User" user "User.Eco2")
		(25 "Edge.Cuts" user)
		(27 "Margin" user)
		(31 "F.CrtYd" user "F.Courtyard")
		(29 "B.CrtYd" user "B.Courtyard")
		(35 "F.Fab" user)
		(33 "B.Fab" user)
	)
	(footprint "antmicro-footprints:R_0402_1005Metric"
		(layer "B.Cu")
		(at 254.801 173.04762 90)
		(descr "Resistor SMD 0402")
		(tags "resistor SMD 0402")
		(property "Reference" "R60"
			(at 0.99762 -0.626 270)
			(layer "B.SilkS")
			(effects
				(font
					(size 0.7 0.7)
					(thickness 0.15)
				)
				(justify left bottom mirror)
			)
		)
		(property "Value" "R_0R_0402"
			(at 0 -1.4 270)
			(layer "B.Fab")
			(effects
				(font
					(size 0.7 0.7)
					(thickness 0.15)
				)
				(justify left bottom mirror)
			)
		)
		(property "Description" "SMD Chip Resistor, Jumper, 0 ohm, 100 mW, 0402 [1005 Metric], Thick Film, General Purpose"
			(at 0 0 90)
			(layer "F.Fab")
			(hide yes)
			(effects
				(font
					(size 1.27 1.27)
					(thickness 0.15)
				)
			)
		)
		(property "Author" "Antmicro"
			(at 427.84862 -81.75338 0)
			(layer "B.Fab")
			(hide yes)
			(effects
				(font
					(size 1 1)
					(thickness 0.15)
				)
				(justify mirror)
			)
		)
		(property "Current" "1A"
			(at 427.84862 -81.75338 0)
			(layer "B.Fab")
			(hide yes)
			(effects
				(font
					(size 1 1)
					(thickness 0.15)
				)
				(justify mirror)
			)
		)
		(property "License" "Apache-2.0"
			(at 427.84862 -81.75338 0)
			(layer "B.Fab")
			(hide yes)
			(effects
				(font
					(size 1 1)
					(thickness 0.15)
				)
				(justify mirror)
			)
		)
		(property "MPN" "ERJ2GE0R00X"
			(at 427.84862 -81.75338 0)
			(layer "B.Fab")
			(hide yes)
			(effects
				(font
					(size 1 1)
					(thickness 0.15)
				)
				(justify mirror)
			)
		)
		(property "Manufacturer" "Panasonic"
			(at 427.84862 -81.75338 0)
			(layer "B.Fab")
			(hide yes)
			(effects
				(font
					(size 1 1)
					(thickness 0.15)
				)
				(justify mirror)
			)
		)
		(property "Tolerance" ""
			(at 427.84862 -81.75338 0)
			(layer "B.Fab")
			(hide yes)
			(effects
				(font
					(size 1 1)
					(thickness 0.15)
				)
				(justify mirror)
			)
		)
		(property "Val" "0R"
			(at 427.84862 -81.75338 0)
			(layer "B.Fab")
			(hide yes)
			(effects
				(font
					(size 1 1)
					(thickness 0.15)
				)
				(justify mirror)
			)
		)
		(sheetname "Power supply")
		(sheetfile "power-supply.kicad_sch")
		(attr smd)
		(fp_rect
			(start -0.925 0.47)
			(end 0.925 -0.47)
			(stroke
				(width 0.05)
				(type default)
			)
			(fill no)
			(layer "B.CrtYd")
		)
		(fp_rect
			(start -0.5 0.25)
			(end 0.5 -0.25)
			(stroke
				(width 0.15)
				(type solid)
			)
			(fill no)
			(layer "B.Fab")
		)
		(pad "1" smd roundrect
			(at -0.48 0 90)
			(size 0.59 0.64)
			(layers "B.Cu" "B.Mask" "B.Paste")
			(roundrect_rratio 0.25)
			(net 344 "Net-(Q18-D)")
			(pintype "passive")
		)
		(pad "2" smd roundrect
			(at 0.48 0 90)
			(size 0.59 0.64)
			(layers "B.Cu" "B.Mask" "B.Paste")
			(roundrect_rratio 0.25)
			(net 798 "/Power supply/POE_ACTIVE")
			(pintype "passive")
		)
	)
	(footprint "antmicro-footprints:C_0603_1608Metric"
		(layer "B.Cu")
		(at 217.7 113.9 -90)
		(descr "Capacitor SMD 0603")
		(tags "capacitor 0603")
		(property "Reference" "C7"
			(at -0.8 -1.41 90)
			(layer "B.SilkS")
			(effects
				(font
					(size 0.7 0.7)
					(thickness 0.15)
				)
				(justify left bottom mirror)
			)
		)
		(property "Value" "C_47u_0603"
			(at 0 -1.6 90)
			(layer "B.Fab")
			(effects
				(font
					(size 0.7 0.7)
					(thickness 0.15)
				)
				(justify left bottom mirror)
			)
		)
		(property "Description" "SMD Multilayer Ceramic Capacitor, 47 µF, 6.3 V, 0603 [1608 Metric], ± 20%, X5R, GRM Series"
			(at 0 0 270)
			(layer "F.Fab")
			(hide yes)
			(effects
				(font
					(size 1.27 1.27)
					(thickness 0.15)
				)
			)
		)
		(property "Author" "Antmicro"
			(at 103.8 331.6 0)
			(layer "B.Fab")
			(hide yes)
			(effects
				(font
					(size 1 1)
					(thickness 0.15)
				)
				(justify mirror)
			)
		)
		(property "Dielectric" ""
			(at 103.8 331.6 0)
			(layer "B.Fab")
			(hide yes)
			(effects
				(font
					(size 1 1)
					(thickness 0.15)
				)
				(justify mirror)
			)
		)
		(property "License" "Apache-2.0"
			(at 103.8 331.6 0)
			(layer "B.Fab")
			(hide yes)
			(effects
				(font
					(size 1 1)
					(thickness 0.15)
				)
				(justify mirror)
			)
		)
		(property "MPN" "GRM188R60J476ME15D"
			(at 103.8 331.6 0)
			(layer "B.Fab")
			(hide yes)
			(effects
				(font
					(size 1 1)
					(thickness 0.15)
				)
				(justify mirror)
			)
		)
		(property "Manufacturer" "Murata"
			(at 103.8 331.6 0)
			(layer "B.Fab")
			(hide yes)
			(effects
				(font
					(size 1 1)
					(thickness 0.15)
				)
				(justify mirror)
			)
		)
		(property "Val" "47u"
			(at 103.8 331.6 0)
			(layer "B.Fab")
			(hide yes)
			(effects
				(font
					(size 1 1)
					(thickness 0.15)
				)
				(justify mirror)
			)
		)
		(property "Voltage" ""
			(at 103.8 331.6 0)
			(layer "B.Fab")
			(hide yes)
			(effects
				(font
					(size 1 1)
					(thickness 0.15)
				)
				(justify mirror)
			)
		)
		(sheetname "FPGA Bank 16 & 17")
		(sheetfile "fpga-bank-16-17.kicad_sch")
		(attr smd)
		(fp_line
			(start -0.15 0.4)
			(end 0.15 0.4)
			(stroke
				(width 0.15)
				(type solid)
			)
			(layer "B.SilkS")
		)
		(fp_line
			(start -0.15 -0.4)
			(end 0.15 -0.4)
			(stroke
				(width 0.15)
				(type solid)
			)
			(layer "B.SilkS")
		)
		(fp_rect
			(start -1.25 0.65)
			(end 1.25 -0.65)
			(stroke
				(width 0.05)
				(type solid)
			)
			(fill no)
			(layer "B.CrtYd")
		)
		(fp_rect
			(start -0.8 0.4)
			(end 0.8 -0.4)
			(stroke
				(width 0.15)
				(type solid)
			)
			(fill no)
			(layer "B.Fab")
		)
		(pad "1" smd roundrect
			(at -0.7 0 270)
			(size 0.8 1)
			(layers "B.Cu" "B.Mask" "B.Paste")
			(roundrect_rratio 0.2)
			(net 1 "GND")
			(pintype "passive")
		)
		(pad "2" smd roundrect
			(at 0.7 0 270)
			(size 0.8 1)
			(layers "B.Cu" "B.Mask" "B.Paste")
			(roundrect_rratio 0.2)
			(net 3 "VCC_USR_B")
			(pintype "passive")
		)
	)
	(footprint "antmicro-footprints:R_0402_1005Metric"
		(layer "B.Cu")
		(at 219.399999 77.899999 -90)
		(descr "Resistor SMD 0402")
		(tags "resistor SMD 0402")
		(property "Reference" "R122"
			(at -3.599999 -0.325001 90)
			(layer "B.SilkS")
			(effects
				(font
					(size 0.7 0.7)
					(thickness 0.15)
				)
				(justify left bottom mirror)
			)
		)
		(property "Value" "R_100R_0402"
			(at 0 -1.4 90)
			(layer "B.Fab")
			(effects
				(font
					(size 0.7 0.7)
					(thickness 0.15)
				)
				(justify left bottom mirror)
			)
		)
		(property "Description" "SMD Chip Resistor, 100 ohm, ± 1%, 62.5 mW, 0402 [1005 Metric], Thick Film, General Purpose"
			(at 0 0 270)
			(layer "F.Fab")
			(hide yes)
			(effects
				(font
					(size 1.27 1.27)
					(thickness 0.15)
				)
			)
		)
		(property "Author" "Antmicro"
			(at 141.5 297.299998 0)
			(layer "B.Fab")
			(hide yes)
			(effects
				(font
					(size 1 1)
					(thickness 0.15)
				)
				(justify mirror)
			)
		)
		(property "License" "Apache-2.0"
			(at 141.5 297.299998 0)
			(layer "B.Fab")
			(hide yes)
			(effects
				(font
					(size 1 1)
					(thickness 0.15)
				)
				(justify mirror)
			)
		)
		(property "MPN" "CR0402-FX-1000GLF"
			(at 141.5 297.299998 0)
			(layer "B.Fab")
			(hide yes)
			(effects
				(font
					(size 1 1)
					(thickness 0.15)
				)
				(justify mirror)
			)
		)
		(property "Manufacturer" "Bourns"
			(at 141.5 297.299998 0)
			(layer "B.Fab")
			(hide yes)
			(effects
				(font
					(size 1 1)
					(thickness 0.15)
				)
				(justify mirror)
			)
		)
		(property "Tolerance" "1%"
			(at 141.5 297.299998 0)
			(layer "B.Fab")
			(hide yes)
			(effects
				(font
					(size 1 1)
					(thickness 0.15)
				)
				(justify mirror)
			)
		)
		(property "Val" "100R"
			(at 141.5 297.299998 0)
			(layer "B.Fab")
			(hide yes)
			(effects
				(font
					(size 1 1)
					(thickness 0.15)
				)
				(justify mirror)
			)
		)
		(sheetname "User GPIO + LED + button + DIP switch")
		(sheetfile "user-gpio.kicad_sch")
		(attr smd)
		(fp_rect
			(start -0.925 0.47)
			(end 0.925 -0.47)
			(stroke
				(width 0.05)
				(type default)
			)
			(fill no)
			(layer "B.CrtYd")
		)
		(fp_rect
			(start -0.5 0.25)
			(end 0.5 -0.25)
			(stroke
				(width 0.15)
				(type solid)
			)
			(fill no)
			(layer "B.Fab")
		)
		(pad "1" smd roundrect
			(at -0.48 0 270)
			(size 0.59 0.64)
			(layers "B.Cu" "B.Mask" "B.Paste")
			(roundrect_rratio 0.25)
			(net 458 "/FPGA Bank 12 & 13/PMOD_A.IO3")
			(pintype "passive")
		)
		(pad "2" smd roundrect
			(at 0.48 0 270)
			(size 0.59 0.64)
			(layers "B.Cu" "B.Mask" "B.Paste")
			(roundrect_rratio 0.25)
			(net 805 "/User GPIO + LED + button + DIP switch/PMOD_A_3")
			(pintype "passive")
		)
	)
	(footprint "antmicro-footprints:R_0402_1005Metric"
		(layer "B.Cu")
		(at 170.25 169.3125 -90)
		(descr "Resistor SMD 0402")
		(tags "resistor SMD 0402")
		(property "Reference" "R301"
			(at 0.7375 -0.375 90)
			(layer "B.SilkS")
			(effects
				(font
					(size 0.7 0.7)
					(thickness 0.15)
				)
				(justify left bottom mirror)
			)
		)
		(property "Value" "R_0R_0402"
			(at 0 -1.4 90)
			(layer "B.Fab")
			(effects
				(font
					(size 0.7 0.7)
					(thickness 0.15)
				)
				(justify left bottom mirror)
			)
		)
		(property "Description" "SMD Chip Resistor, Jumper, 0 ohm, 100 mW, 0402 [1005 Metric], Thick Film, General Purpose"
			(at 0 0 270)
			(layer "F.Fab")
			(hide yes)
			(effects
				(font
					(size 1.27 1.27)
					(thickness 0.15)
				)
			)
		)
		(property "Author" "Antmicro"
			(at 0.9375 339.5625 0)
			(layer "B.Fab")
			(hide yes)
			(effects
				(font
					(size 1 1)
					(thickness 0.15)
				)
				(justify mirror)
			)
		)
		(property "Current" "1A"
			(at 0.9375 339.5625 0)
			(layer "B.Fab")
			(hide yes)
			(effects
				(font
					(size 1 1)
					(thickness 0.15)
				)
				(justify mirror)
			)
		)
		(property "DNP" "DNP"
			(at 0.9375 339.5625 0)
			(layer "B.Fab")
			(hide yes)
			(effects
				(font
					(size 1 1)
					(thickness 0.15)
				)
				(justify mirror)
			)
		)
		(property "License" "Apache-2.0"
			(at 0.9375 339.5625 0)
			(layer "B.Fab")
			(hide yes)
			(effects
				(font
					(size 1 1)
					(thickness 0.15)
				)
				(justify mirror)
			)
		)
		(property "MPN" "ERJ2GE0R00X"
			(at 0.9375 339.5625 0)
			(layer "B.Fab")
			(hide yes)
			(effects
				(font
					(size 1 1)
					(thickness 0.15)
				)
				(justify mirror)
			)
		)
		(property "Manufacturer" "Panasonic"
			(at 0.9375 339.5625 0)
			(layer "B.Fab")
			(hide yes)
			(effects
				(font
					(size 1 1)
					(thickness 0.15)
				)
				(justify mirror)
			)
		)
		(property "Tolerance" ""
			(at 0.9375 339.5625 0)
			(layer "B.Fab")
			(hide yes)
			(effects
				(font
					(size 1 1)
					(thickness 0.15)
				)
				(justify mirror)
			)
		)
		(property "Val" "0R"
			(at 0.9375 339.5625 0)
			(layer "B.Fab")
			(hide yes)
			(effects
				(font
					(size 1 1)
					(thickness 0.15)
				)
				(justify mirror)
			)
		)
		(property "dnp" ""
			(at 0.9375 339.5625 0)
			(layer "B.Fab")
			(hide yes)
			(effects
				(font
					(size 1 1)
					(thickness 0.15)
				)
				(justify mirror)
			)
		)
		(property "exclude_from_bom" ""
			(at 0.9375 339.5625 0)
			(layer "B.Fab")
			(hide yes)
			(effects
				(font
					(size 1 1)
					(thickness 0.15)
				)
				(justify mirror)
			)
		)
		(sheetname "DC-DC Converters")
		(sheetfile "dc-dc.kicad_sch")
		(attr smd exclude_from_bom)
		(fp_rect
			(start -0.925 0.47)
			(end 0.925 -0.47)
			(stroke
				(width 0.05)
				(type default)
			)
			(fill no)
			(layer "B.CrtYd")
		)
		(fp_rect
			(start -0.5 0.25)
			(end 0.5 -0.25)
			(stroke
				(width 0.15)
				(type solid)
			)
			(fill no)
			(layer "B.Fab")
		)
		(pad "1" smd roundrect
			(at -0.48 0 270)
			(size 0.59 0.64)
			(layers "B.Cu" "B.Mask" "B.Paste")
			(roundrect_rratio 0.25)
			(net 1217 "/DC-DC Converters/SENSE_3V3_1_N")
			(pintype "passive")
		)
		(pad "2" smd roundrect
			(at 0.48 0 270)
			(size 0.59 0.64)
			(layers "B.Cu" "B.Mask" "B.Paste")
			(roundrect_rratio 0.25)
			(net 958 "/DC-DC Converters/FB5")
			(pintype "passive")
		)
	)
	(footprint "antmicro-footprints:R_0402_1005Metric"
		(layer "B.Cu")
		(at 266.8 84 -90)
		(descr "Resistor SMD 0402")
		(tags "resistor SMD 0402")
		(property "Reference" "R141"
			(at -1.275 -1.3 90)
			(layer "B.SilkS")
			(effects
				(font
					(size 0.7 0.7)
					(thickness 0.15)
				)
				(justify left bottom mirror)
			)
		)
		(property "Value" "R_10k_0402"
			(at 0 -1.4 90)
			(layer "B.Fab")
			(effects
				(font
					(size 0.7 0.7)
					(thickness 0.15)
				)
				(justify left bottom mirror)
			)
		)
		(property "Description" "SMD Chip Resistor, 10 kohm, ± 1%, 62.5 mW, 0402 [1005 Metric], Thick Film, General Purpose"
			(at 0 0 270)
			(layer "F.Fab")
			(hide yes)
			(effects
				(font
					(size 1.27 1.27)
					(thickness 0.15)
				)
			)
		)
		(property "Author" "Antmicro"
			(at 182.8 350.8 0)
			(layer "B.Fab")
			(hide yes)
			(effects
				(font
					(size 1 1)
					(thickness 0.15)
				)
				(justify mirror)
			)
		)
		(property "License" "Apache-2.0"
			(at 182.8 350.8 0)
			(layer "B.Fab")
			(hide yes)
			(effects
				(font
					(size 1 1)
					(thickness 0.15)
				)
				(justify mirror)
			)
		)
		(property "MPN" "CR0402-FX-1002GLF"
			(at 182.8 350.8 0)
			(layer "B.Fab")
			(hide yes)
			(effects
				(font
					(size 1 1)
					(thickness 0.15)
				)
				(justify mirror)
			)
		)
		(property "Manufacturer" "Bourns"
			(at 182.8 350.8 0)
			(layer "B.Fab")
			(hide yes)
			(effects
				(font
					(size 1 1)
					(thickness 0.15)
				)
				(justify mirror)
			)
		)
		(property "Tolerance" "1%"
			(at 182.8 350.8 0)
			(layer "B.Fab")
			(hide yes)
			(effects
				(font
					(size 1 1)
					(thickness 0.15)
				)
				(justify mirror)
			)
		)
		(property "Val" "10k"
			(at 182.8 350.8 0)
			(layer "B.Fab")
			(hide yes)
			(effects
				(font
					(size 1 1)
					(thickness 0.15)
				)
				(justify mirror)
			)
		)
		(sheetname "User GPIO + LED + button + DIP switch")
		(sheetfile "user-gpio.kicad_sch")
		(attr smd)
		(fp_rect
			(start -0.925 0.47)
			(end 0.925 -0.47)
			(stroke
				(width 0.05)
				(type default)
			)
			(fill no)
			(layer "B.CrtYd")
		)
		(fp_rect
			(start -0.5 0.25)
			(end 0.5 -0.25)
			(stroke
				(width 0.15)
				(type solid)
			)
			(fill no)
			(layer "B.Fab")
		)
		(pad "1" smd roundrect
			(at -0.48 0 270)
			(size 0.59 0.64)
			(layers "B.Cu" "B.Mask" "B.Paste")
			(roundrect_rratio 0.25)
			(net 26 "+1V8")
			(pintype "passive")
		)
		(pad "2" smd roundrect
			(at 0.48 0 270)
			(size 0.59 0.64)
			(layers "B.Cu" "B.Mask" "B.Paste")
			(roundrect_rratio 0.25)
			(net 13 "/USER_IO.BUTTON1")
			(pintype "passive")
		)
	)
	(footprint "antmicro-footprints:NetTie-2_SMD_Pad0.127mm"
		(layer "B.Cu")
		(at 251.701 148.4 90)
		(descr "Net tie, 2 pin, 0.127mm  SMD pads")
		(tags "net tie")
		(property "Reference" "NT5"
			(at -0.128 1.345 270)
			(layer "B.SilkS")
			(hide yes)
			(effects
				(font
					(size 0.7 0.7)
					(thickness 0.15)
				)
				(justify left bottom mirror)
			)
		)
		(property "Value" "Net-Tie_2"
			(at 0 -1.199 270)
			(layer "B.Fab")
			(effects
				(font
					(size 0.7 0.7)
					(thickness 0.15)
				)
				(justify left bottom mirror)
			)
		)
		(property "Description" "Net tie, 2 pins"
			(at 0 0 90)
			(layer "F.Fab")
			(hide yes)
			(effects
				(font
					(size 1.27 1.27)
					(thickness 0.15)
				)
			)
		)
		(property "Author" "Antmicro"
			(at 400.101 -103.301 0)
			(layer "B.Fab")
			(hide yes)
			(effects
				(font
					(size 1 1)
					(thickness 0.15)
				)
				(justify mirror)
			)
		)
		(property "License" "Apache-2.0"
			(at 400.101 -103.301 0)
			(layer "B.Fab")
			(hide yes)
			(effects
				(font
					(size 1 1)
					(thickness 0.15)
				)
				(justify mirror)
			)
		)
		(property "MPN" ""
			(at 400.101 -103.301 0)
			(layer "B.Fab")
			(hide yes)
			(effects
				(font
					(size 1 1)
					(thickness 0.15)
				)
				(justify mirror)
			)
		)
		(property "Manufacturer" ""
			(at 400.101 -103.301 0)
			(layer "B.Fab")
			(hide yes)
			(effects
				(font
					(size 1 1)
					(thickness 0.15)
				)
				(justify mirror)
			)
		)
		(sheetname "FPGA Config")
		(sheetfile "fpga-config.kicad_sch")
		(attr exclude_from_pos_files)
		(net_tie_pad_groups "1, 2")
		(fp_poly
			(pts
				(xy -0.0635 0.0635) (xy 0.0625 0.0635) (xy 0.0625 -0.0635) (xy -0.0635 -0.0635)
			)
			(stroke
				(width 0)
				(type solid)
			)
			(fill yes)
			(layer "B.Cu")
		)
		(pad "1" smd roundrect
			(at -0.127 0 270)
			(size 0.127 0.127)
			(layers "B.Cu")
			(roundrect_rratio 0.5)
			(chamfer_ratio 0)
			(chamfer top_left bottom_left)
			(net 1314 "/SUP_MCU.FPGA_M2")
			(pinfunction "1")
			(pintype "passive")
		)
		(pad "2" smd roundrect
			(at 0.126 0 90)
			(size 0.127 0.127)
			(layers "B.Cu")
			(roundrect_rratio 0.5)
			(chamfer_ratio 0)
			(chamfer top_left bottom_left)
			(net 298 "/FPGA Config/MODE2")
			(pinfunction "2")
			(pintype "passive")
		)
	)
)
